#ISCELL
  mstr_misc dns *
  *
#ISCELL
  pure_quanta quanta_title_block_c *
  *
#ISCELL
  standard offpage *
  page191_i1
#CELL
  pure_quanta q_res *
  page191_i10
#CELL
  pure_quanta q_cap *
  page191_i11
#ISCELL
  pure_quanta_power universal_gnd *
  page191_i12
#CELL
  pure_quanta q_cap *
  page191_i13
#CELL
  pure_quanta q_res *
  page191_i14
#ISCELL
  pure_quanta_power vcc_core *
  page191_i15
#ISCELL
  standard offpage *
  page191_i16
#ISCELL
  pure_quanta_power universal_gnd *
  page191_i17
#CELL
  pure_quanta q_cap *
  page191_i18
#CELL
  pure_quanta q_cap *
  page191_i19
#CELL
  pure_quanta q_cap *
  page191_i2
#CELL
  pure_quanta q_cap *
  page191_i20
#CELL
  pure_quanta q_res *
  page191_i21
#CELL
  pure_quanta q_cap *
  page191_i22
#CELL
  pure_quanta q_res *
  page191_i23
#ISCELL
  pure_quanta_power universal_gnd *
  page191_i24
#CELL
  pure_quanta q_inductor *
  page191_i25
#CELL
  pure_quanta q_inductor4p_14 *
  page191_i26
#ISCELL
  standard offpage *
  page191_i27
#CELL
  pure_quanta q_cap *
  page191_i28
#ISCELL
  pure_quanta_power universal_gnd *
  page191_i29
#ISCELL
  pure_quanta_power universal_gnd *
  page191_i3
#CELL
  pure_quanta q_cap *
  page191_i30
#CELL
  pure_quanta q_cap *
  page191_i31
#CELL
  pure_quanta q_cap *
  page191_i32
#CELL
  pure_quanta q_cap *
  page191_i33
#CELL
  pure_quanta q_cap *
  page191_i34
#ISCELL
  pure_quanta_power universal_gnd *
  page191_i35
#ISCELL
  pure_quanta_power vcc_core *
  page191_i36
#ISCELL
  pure_quanta_power vcc_core *
  page191_i37
#CELL
  pure_quanta isl99390frztr5935 *
  page191_i38
#ISCELL
  pure_quanta_power universal_gnd *
  page191_i4
#ISCELL
  standard offpage *
  page191_i5
#ISCELL
  standard offpage *
  page191_i6
#CELL
  pure_quanta q_res *
  page191_i7
#ISCELL
  pure_quanta_power universal_gnd *
  page191_i8
#ISCELL
  pure_quanta_power universal_gnd *
  page191_i9
